# BASEBOARD_FAB2 (Tioga Pass) — schematic netlist excerpt (pin names and nets, part order shuffled) for the footprints in the layout excerpt that follows; sources: Cadence DE-HDL packaged netlist, KiCad conversion of Wiwynn_Tioga_Pass_MB.brd

R2T9  RES  75 1.0% CHIP  pkg 0402  page 154 : A = SPI_CS0_SECONDARY_N ; B = SPI_CS0_SECONDARY_R_N
C3R3  CAP_A  0.1UF 16V 10% X7R  pkg 0402V  page 192 : A = P3V3_STBY ; B = GND
C8P34  CAP  100UF 4V 20% X5R  pkg 0805  page 225 : A = PVDDQ_GHJ ; B = GND

(kicad_pcb
	(version 20260206)
	(generator "pcbnew")
	(generator_version "10.0")
	(general
		(thickness 1.6)
		(legacy_teardrops no)
	)
	(paper "A4")
	(title_block
		(title "Wiwynn_Tioga_Pass_MB.brd")
		(comment 1 "Tioga Pass / footprints 2579-2581 of 4770")
	)
	(layers
		(0 "F.Cu" signal "TOP")
		(4 "In1.Cu" signal "L2GND")
		(6 "In2.Cu" signal "L3")
		(8 "In3.Cu" signal "L4GND")
		(10 "In4.Cu" signal "L5")
		(12 "In5.Cu" signal "L6GND")
		(14 "In6.Cu" signal "L7VCC")
		(16 "In7.Cu" signal "L8VCC")
		(18 "In8.Cu" signal "L9GND")
		(20 "In9.Cu" signal "L10")
		(22 "In10.Cu" signal "L11GND")
		(24 "In11.Cu" signal "L12")
		(26 "In12.Cu" signal "L13GND")
		(2 "B.Cu" signal "BOTTOM")
		(9 "F.Adhes" user "F.Adhesive")
		(11 "B.Adhes" user "B.Adhesive")
		(13 "F.Paste" user "Package Geometry/Pastemask Top")
		(15 "B.Paste" user "Package Geometry/Pastemask Bottom")
		(5 "F.SilkS" user "Ref Des/Silkscreen Top")
		(7 "B.SilkS" user "Ref Des/Silkscreen Bottom")
		(1 "F.Mask" user "Board Geometry/Soldermask Top")
		(3 "B.Mask" user "Board Geometry/Soldermask Bottom")
		(17 "Dwgs.User" user "User.Drawings")
		(19 "Cmts.User" user "User.Comments")
		(21 "Eco1.User" user "User.Eco1")
		(23 "Eco2.User" user "User.Eco2")
		(25 "Edge.Cuts" user "Board Geometry/Outline")
		(27 "Margin" user)
		(31 "F.CrtYd" user "Package Geometry/Place Bound Top")
		(29 "B.CrtYd" user "Package Geometry/Place Bound Bottom")
		(35 "F.Fab" user "Ref Des/Assembly Top")
		(33 "B.Fab" user "Ref Des/Assembly Bottom")
	)
	(footprint ""
		(layer "B.Cu")
		(at 394.335 -65.3415 90)
		(property "Reference" "R2T9"
			(at 0 0 90)
			(layer "B.SilkS")
			(hide yes)
			(effects
				(font
					(size 1.27 1.27)
				)
				(justify mirror)
			)
		)
		(property "Value" ""
			(at 0 0 90)
			(layer "B.Fab")
			(effects
				(font
					(size 1.27 1.27)
				)
				(justify mirror)
			)
		)
		(duplicate_pad_numbers_are_jumpers no)
		(fp_poly
			(pts
				(xy 0.2794 -0.1016) (xy -0.2794 -0.1016) (xy -0.2794 0.9906) (xy 0.2794 0.9906)
			)
			(stroke
				(width 0)
				(type default)
			)
			(fill no)
			(layer "B.CrtYd")
		)
		(fp_line
			(start 0.2794 -0.1016)
			(end 0.2794 0.9906)
			(stroke
				(width 0.1)
				(type default)
			)
			(layer "B.Fab")
		)
		(fp_line
			(start -0.2794 -0.1016)
			(end 0.2794 -0.1016)
			(stroke
				(width 0.1)
				(type default)
			)
			(layer "B.Fab")
		)
		(fp_line
			(start 0.2794 0.9906)
			(end -0.2794 0.9906)
			(stroke
				(width 0.1)
				(type default)
			)
			(layer "B.Fab")
		)
		(fp_line
			(start -0.2794 0.9906)
			(end -0.2794 -0.1016)
			(stroke
				(width 0.1)
				(type default)
			)
			(layer "B.Fab")
		)
		(pad "1" smd rect
			(at 0 0 270)
			(size 0.508 0.508)
			(layers "B.Cu" "B.Mask" "B.Paste")
			(net "SPI_CS0_SECONDARY_N")
		)
		(pad "2" smd rect
			(at 0 0.889 270)
			(size 0.508 0.508)
			(layers "B.Cu" "B.Mask" "B.Paste")
			(net "SPI_CS0_SECONDARY_R_N")
		)
		(zone
			(layer "B.Cu")
			(hatch none 0.5)
			(connect_pads
				(clearance 0)
			)
			(min_thickness 0.25)
			(keepout
				(tracks allowed)
				(vias not_allowed)
				(pads allowed)
				(copperpour not_allowed)
				(footprints allowed)
			)
			(placement
				(enabled no)
				(sheetname "")
			)
			(fill
				(thermal_gap 0.5)
				(thermal_bridge_width 0.5)
				(island_removal_mode 0)
			)
			(polygon
				(pts
					(xy 394.589 -65.5955) (xy 394.589 -65.0875) (xy 394.97 -65.0875) (xy 394.97 -65.5955)
				)
			)
		)
		(zone
			(layer "B.Cu")
			(hatch none 0.5)
			(connect_pads
				(clearance 0)
			)
			(min_thickness 0.25)
			(keepout
				(tracks not_allowed)
				(vias allowed)
				(pads allowed)
				(copperpour not_allowed)
				(footprints allowed)
			)
			(placement
				(enabled no)
				(sheetname "")
			)
			(fill
				(thermal_gap 0.5)
				(thermal_bridge_width 0.5)
				(island_removal_mode 0)
			)
			(polygon
				(pts
					(xy 394.97 -65.5955) (xy 394.97 -65.0875) (xy 394.589 -65.0875) (xy 394.589 -65.5955)
				)
			)
		)
	)
	(footprint ""
		(layer "B.Cu")
		(at 102.946454 -68.17614 180)
		(property "Reference" "C8P34"
			(at 0 0 0)
			(layer "B.SilkS")
			(hide yes)
			(effects
				(font
					(size 1.27 1.27)
				)
				(justify mirror)
			)
		)
		(property "Value" ""
			(at 0 0 0)
			(layer "B.Fab")
			(effects
				(font
					(size 1.27 1.27)
				)
				(justify mirror)
			)
		)
		(duplicate_pad_numbers_are_jumpers no)
		(fp_poly
			(pts
				(xy 0.7239 -0.2159) (xy -0.7239 -0.2159) (xy -0.7239 1.9939) (xy 0.7239 1.9939)
			)
			(stroke
				(width 0)
				(type default)
			)
			(fill no)
			(layer "B.CrtYd")
		)
		(fp_line
			(start 0.7239 1.9939)
			(end -0.7239 1.9939)
			(stroke
				(width 0.1)
				(type default)
			)
			(layer "B.Fab")
		)
		(fp_line
			(start 0.7239 -0.2159)
			(end 0.7239 1.9939)
			(stroke
				(width 0.1)
				(type default)
			)
			(layer "B.Fab")
		)
		(fp_line
			(start -0.7239 1.9939)
			(end -0.7239 -0.2159)
			(stroke
				(width 0.1)
				(type default)
			)
			(layer "B.Fab")
		)
		(fp_line
			(start -0.7239 -0.2159)
			(end 0.7239 -0.2159)
			(stroke
				(width 0.1)
				(type default)
			)
			(layer "B.Fab")
		)
		(pad "1" smd rect
			(at 0 0)
			(size 1.27 1.016)
			(layers "B.Cu" "B.Mask" "B.Paste")
			(net "PVDDQ_GHJ")
		)
		(pad "2" smd rect
			(at 0 1.778)
			(size 1.27 1.016)
			(layers "B.Cu" "B.Mask" "B.Paste")
			(net "GND")
		)
		(zone
			(layer "B.Cu")
			(hatch none 0.5)
			(connect_pads
				(clearance 0)
			)
			(min_thickness 0.25)
			(keepout
				(tracks not_allowed)
				(vias allowed)
				(pads allowed)
				(copperpour not_allowed)
				(footprints allowed)
			)
			(placement
				(enabled no)
				(sheetname "")
			)
			(fill
				(thermal_gap 0.5)
				(thermal_bridge_width 0.5)
				(island_removal_mode 0)
			)
			(polygon
				(pts
					(xy 102.311454 -68.68414) (xy 103.581454 -68.68414) (xy 103.581454 -69.44614) (xy 102.311454 -69.44614)
				)
			)
		)
	)
	(footprint ""
		(layer "B.Cu")
		(at 373.945404 -75.495404)
		(property "Reference" "C3R3"
			(at 0 0 0)
			(layer "B.SilkS")
			(hide yes)
			(effects
				(font
					(size 1.27 1.27)
				)
				(justify mirror)
			)
		)
		(property "Value" ""
			(at 0 0 0)
			(layer "B.Fab")
			(effects
				(font
					(size 1.27 1.27)
				)
				(justify mirror)
			)
		)
		(duplicate_pad_numbers_are_jumpers no)
		(fp_rect
			(start 0.2794 0.9144)
			(end -0.2794 -0.1143)
			(stroke
				(width 0)
				(type default)
			)
			(fill no)
			(layer "B.CrtYd")
		)
		(fp_line
			(start -0.2794 -0.1143)
			(end -0.2794 0.9144)
			(stroke
				(width 0.1)
				(type default)
			)
			(layer "B.Fab")
		)
		(fp_line
			(start -0.2794 0.9144)
			(end 0.2794 0.9144)
			(stroke
				(width 0.1)
				(type default)
			)
			(layer "B.Fab")
		)
		(fp_line
			(start 0.2794 -0.1143)
			(end -0.2794 -0.1143)
			(stroke
				(width 0.1)
				(type default)
			)
			(layer "B.Fab")
		)
		(fp_line
			(start 0.2794 0.9144)
			(end 0.2794 -0.1143)
			(stroke
				(width 0.1)
				(type default)
			)
			(layer "B.Fab")
		)
		(pad "1" smd custom
			(at 0 0 270)
			(size 0.10414 0.10414)
			(layers "B.Cu" "B.Mask" "B.Paste")
			(net "P3V3_STBY")
			(options
				(clearance outline)
				(anchor circle)
			)
			(primitives
				(gr_poly
					(pts
						(xy -0.20828 -0.08636) (xy -0.20828 0.08636) (xy -0.08636 0.20828) (xy 0.086614 0.20828) (xy 0.20828 0.086614)
						(xy 0.20828 -0.08636) (xy 0.08636 -0.20828) (xy -0.08636 -0.20828)
					)
					(width 0)
					(fill yes)
				)
			)
		)
		(pad "2" smd custom
			(at 0 0.8001 270)
			(size 0.10414 0.10414)
			(layers "B.Cu" "B.Mask" "B.Paste")
			(net "GND")
			(options
				(clearance outline)
				(anchor circle)
			)
			(primitives
				(gr_poly
					(pts
						(xy -0.20828 -0.08636) (xy -0.20828 0.08636) (xy -0.08636 0.20828) (xy 0.086614 0.20828) (xy 0.20828 0.086614)
						(xy 0.20828 -0.08636) (xy 0.08636 -0.20828) (xy -0.08636 -0.20828)
					)
					(width 0)
					(fill yes)
				)
			)
		)
		(zone
			(layer "B.Cu")
			(hatch none 0.5)
			(connect_pads
				(clearance 0)
			)
			(min_thickness 0.25)
			(keepout
				(tracks allowed)
				(vias not_allowed)
				(pads allowed)
				(copperpour not_allowed)
				(footprints allowed)
			)
			(placement
				(enabled no)
				(sheetname "")
			)
			(fill
				(thermal_gap 0.5)
				(thermal_bridge_width 0.5)
				(island_removal_mode 0)
			)
			(polygon
				(pts
					(xy 374.033034 -75.285854) (xy 374.033034 -74.904854) (xy 373.857774 -74.904854) (xy 373.85752 -75.285854)
				)
			)
		)
		(zone
			(layer "B.Cu")
			(hatch none 0.5)
			(connect_pads
				(clearance 0)
			)
			(min_thickness 0.25)
			(keepout
				(tracks not_allowed)
				(vias allowed)
				(pads allowed)
				(copperpour not_allowed)
				(footprints allowed)
			)
			(placement
				(enabled no)
				(sheetname "")
			)
			(fill
				(thermal_gap 0.5)
				(thermal_bridge_width 0.5)
				(island_removal_mode 0)
			)
			(polygon
				(pts
					(xy 374.033034 -75.285854) (xy 374.033034 -74.904854) (xy 373.857774 -74.904854) (xy 373.85752 -75.285854)
				)
			)
		)
	)
)
